# T6G (Grand Teton) — schematic netlist excerpt (pin names and nets, part order shuffled) for the footprints in the layout excerpt that follows; sources: Cadence DE-HDL packaged netlist, KiCad conversion of 04192023_DAF0TMB3IC0_F0TG_MB_C_brd_V02_OCP.brd

R992  Q_RES  33 5% CHIP  pkg 0402LF  page 80 : A = FM_SYS_THROTTLE_R_N ; B = FM_SYS_THROTTLE_N
R254  Q_RES  0 5% CHIP  pkg 0402LF  page 81 : A = RST_CPU0_PERST0_N ; B = RST_CPU0_PERST0_R_N
C1009  Q_CAP  0.1UF 10V 10% X7S  pkg C0201  page 312 : A = P0V9_CPU0_RT_2D ; B = GND

(kicad_pcb
	(version 20260206)
	(generator "pcbnew")
	(generator_version "10.0")
	(general
		(thickness 1.6)
		(legacy_teardrops no)
	)
	(paper "A4")
	(title_block
		(title "04192023_DAF0TMB3IC0_F0TG_MB_C_brd_V02_OCP.brd")
		(comment 1 "Grand Teton / footprints 7634-7636 of 8354")
	)
	(layers
		(0 "F.Cu" signal "TOP")
		(4 "In1.Cu" signal "GND")
		(6 "In2.Cu" signal "IN1")
		(8 "In3.Cu" signal "GND1")
		(10 "In4.Cu" signal "IN2")
		(12 "In5.Cu" signal "GND2")
		(14 "In6.Cu" signal "IN3")
		(16 "In7.Cu" signal "GND3")
		(18 "In8.Cu" signal "VCC")
		(20 "In9.Cu" signal "VCC1")
		(22 "In10.Cu" signal "GND4")
		(24 "In11.Cu" signal "IN4")
		(26 "In12.Cu" signal "GND5")
		(28 "In13.Cu" signal "IN5")
		(30 "In14.Cu" signal "GND6")
		(32 "In15.Cu" signal "IN6")
		(34 "In16.Cu" signal "GND7")
		(2 "B.Cu" signal "BOTTOM")
		(9 "F.Adhes" user "F.Adhesive")
		(11 "B.Adhes" user "B.Adhesive")
		(13 "F.Paste" user "Package Geometry/Pastemask Top")
		(15 "B.Paste" user "Package Geometry/Pastemask Bottom")
		(5 "F.SilkS" user "Ref Des/Silkscreen Top")
		(7 "B.SilkS" user "Ref Des/Silkscreen Bottom")
		(1 "F.Mask" user "Board Geometry/Soldermask Top")
		(3 "B.Mask" user "Board Geometry/Soldermask Bottom")
		(17 "Dwgs.User" user "User.Drawings")
		(19 "Cmts.User" user "User.Comments")
		(21 "Eco1.User" user "User.Eco1")
		(23 "Eco2.User" user "User.Eco2")
		(25 "Edge.Cuts" user "Board Geometry/Outline")
		(27 "Margin" user)
		(31 "F.CrtYd" user "Package Geometry/Place Bound Top")
		(29 "B.CrtYd" user "Package Geometry/Place Bound Bottom")
		(35 "F.Fab" user "Ref Des/Assembly Top")
		(33 "B.Fab" user "Ref Des/Assembly Bottom")
	)
	(footprint ""
		(layer "B.Cu")
		(at 171.196 -115.280948)
		(property "Reference" "R992"
			(at 0 0 0)
			(layer "B.SilkS")
			(hide yes)
			(effects
				(font
					(size 1.27 1.27)
				)
				(justify mirror)
			)
		)
		(property "Value" ""
			(at 0 0 0)
			(layer "B.Fab")
			(effects
				(font
					(size 1.27 1.27)
				)
				(justify mirror)
			)
		)
		(duplicate_pad_numbers_are_jumpers no)
		(fp_line
			(start -0.7874 -0.4064)
			(end -0.7874 0.4064)
			(stroke
				(width 0.1524)
				(type default)
			)
			(layer "B.SilkS")
		)
		(fp_line
			(start -0.7874 0.4064)
			(end 0.7874 0.4064)
			(stroke
				(width 0.1524)
				(type default)
			)
			(layer "B.SilkS")
		)
		(fp_line
			(start 0.7874 -0.4064)
			(end -0.7874 -0.4064)
			(stroke
				(width 0.1524)
				(type default)
			)
			(layer "B.SilkS")
		)
		(fp_line
			(start 0.7874 0.4064)
			(end 0.7874 -0.4064)
			(stroke
				(width 0.1524)
				(type default)
			)
			(layer "B.SilkS")
		)
		(fp_line
			(start -0.67945 -0.3048)
			(end -0.67945 0.3048)
			(stroke
				(width 0.1)
				(type default)
			)
			(layer "B.Fab")
		)
		(fp_line
			(start -0.67945 0.3048)
			(end -0.120396 0.3048)
			(stroke
				(width 0.1)
				(type default)
			)
			(layer "B.Fab")
		)
		(fp_line
			(start -0.12065 -0.3048)
			(end -0.67945 -0.3048)
			(stroke
				(width 0.1)
				(type default)
			)
			(layer "B.Fab")
		)
		(fp_line
			(start -0.12065 -0.2794)
			(end -0.12065 -0.3048)
			(stroke
				(width 0.1)
				(type default)
			)
			(layer "B.Fab")
		)
		(fp_line
			(start -0.120396 0.2794)
			(end 0.12065 0.2794)
			(stroke
				(width 0.1)
				(type default)
			)
			(layer "B.Fab")
		)
		(fp_line
			(start -0.120396 0.3048)
			(end -0.120396 0.2794)
			(stroke
				(width 0.1)
				(type default)
			)
			(layer "B.Fab")
		)
		(fp_line
			(start 0.12065 -0.305054)
			(end 0.12065 -0.2794)
			(stroke
				(width 0.1)
				(type default)
			)
			(layer "B.Fab")
		)
		(fp_line
			(start 0.12065 -0.2794)
			(end -0.12065 -0.2794)
			(stroke
				(width 0.1)
				(type default)
			)
			(layer "B.Fab")
		)
		(fp_line
			(start 0.12065 0.2794)
			(end 0.12065 0.3048)
			(stroke
				(width 0.1)
				(type default)
			)
			(layer "B.Fab")
		)
		(fp_line
			(start 0.12065 0.3048)
			(end 0.67945 0.3048)
			(stroke
				(width 0.1)
				(type default)
			)
			(layer "B.Fab")
		)
		(fp_line
			(start 0.67945 -0.305054)
			(end 0.12065 -0.305054)
			(stroke
				(width 0.1)
				(type default)
			)
			(layer "B.Fab")
		)
		(fp_line
			(start 0.67945 0.3048)
			(end 0.67945 -0.305054)
			(stroke
				(width 0.1)
				(type default)
			)
			(layer "B.Fab")
		)
		(pad "1" smd circle
			(at 0.40005 0 180)
			(size 0 0)
			(layers "B.Cu" "B.Mask" "B.Paste")
			(net "FM_SYS_THROTTLE_R_N")
		)
		(pad "2" smd circle
			(at -0.40005 0 180)
			(size 0 0)
			(layers "B.Cu" "B.Mask" "B.Paste")
			(net "FM_SYS_THROTTLE_N")
		)
	)
	(footprint ""
		(layer "B.Cu")
		(at 177.965608 -126.833376 90)
		(property "Reference" "R254"
			(at 0 0 90)
			(layer "B.SilkS")
			(hide yes)
			(effects
				(font
					(size 1.27 1.27)
				)
				(justify mirror)
			)
		)
		(property "Value" ""
			(at 0 0 90)
			(layer "B.Fab")
			(effects
				(font
					(size 1.27 1.27)
				)
				(justify mirror)
			)
		)
		(duplicate_pad_numbers_are_jumpers no)
		(fp_line
			(start 0.7874 -0.4064)
			(end -0.7874 -0.4064)
			(stroke
				(width 0.1524)
				(type default)
			)
			(layer "B.SilkS")
		)
		(fp_line
			(start -0.7874 -0.4064)
			(end -0.7874 0.4064)
			(stroke
				(width 0.1524)
				(type default)
			)
			(layer "B.SilkS")
		)
		(fp_line
			(start 0.7874 0.4064)
			(end 0.7874 -0.4064)
			(stroke
				(width 0.1524)
				(type default)
			)
			(layer "B.SilkS")
		)
		(fp_line
			(start -0.7874 0.4064)
			(end 0.7874 0.4064)
			(stroke
				(width 0.1524)
				(type default)
			)
			(layer "B.SilkS")
		)
		(fp_line
			(start 0.67945 -0.305054)
			(end 0.12065 -0.305054)
			(stroke
				(width 0.1)
				(type default)
			)
			(layer "B.Fab")
		)
		(fp_line
			(start 0.12065 -0.305054)
			(end 0.12065 -0.2794)
			(stroke
				(width 0.1)
				(type default)
			)
			(layer "B.Fab")
		)
		(fp_line
			(start -0.12065 -0.3048)
			(end -0.67945 -0.3048)
			(stroke
				(width 0.1)
				(type default)
			)
			(layer "B.Fab")
		)
		(fp_line
			(start -0.67945 -0.3048)
			(end -0.67945 0.3048)
			(stroke
				(width 0.1)
				(type default)
			)
			(layer "B.Fab")
		)
		(fp_line
			(start 0.12065 -0.2794)
			(end -0.12065 -0.2794)
			(stroke
				(width 0.1)
				(type default)
			)
			(layer "B.Fab")
		)
		(fp_line
			(start -0.12065 -0.2794)
			(end -0.12065 -0.3048)
			(stroke
				(width 0.1)
				(type default)
			)
			(layer "B.Fab")
		)
		(fp_line
			(start 0.12065 0.2794)
			(end 0.12065 0.3048)
			(stroke
				(width 0.1)
				(type default)
			)
			(layer "B.Fab")
		)
		(fp_line
			(start -0.120396 0.2794)
			(end 0.12065 0.2794)
			(stroke
				(width 0.1)
				(type default)
			)
			(layer "B.Fab")
		)
		(fp_line
			(start 0.67945 0.3048)
			(end 0.67945 -0.305054)
			(stroke
				(width 0.1)
				(type default)
			)
			(layer "B.Fab")
		)
		(fp_line
			(start 0.12065 0.3048)
			(end 0.67945 0.3048)
			(stroke
				(width 0.1)
				(type default)
			)
			(layer "B.Fab")
		)
		(fp_line
			(start -0.120396 0.3048)
			(end -0.120396 0.2794)
			(stroke
				(width 0.1)
				(type default)
			)
			(layer "B.Fab")
		)
		(fp_line
			(start -0.67945 0.3048)
			(end -0.120396 0.3048)
			(stroke
				(width 0.1)
				(type default)
			)
			(layer "B.Fab")
		)
		(pad "1" smd circle
			(at 0.40005 0 270)
			(size 0 0)
			(layers "B.Cu" "B.Mask" "B.Paste")
			(net "RST_CPU0_PERST0_N")
		)
		(pad "2" smd circle
			(at -0.40005 0 270)
			(size 0 0)
			(layers "B.Cu" "B.Mask" "B.Paste")
			(net "RST_CPU0_PERST0_R_N")
		)
	)
	(footprint ""
		(layer "B.Cu")
		(at 376.6185 -396.393162 -90)
		(property "Reference" "C1009"
			(at 0 0 90)
			(layer "B.SilkS")
			(hide yes)
			(effects
				(font
					(size 1.27 1.27)
				)
				(justify mirror)
			)
		)
		(property "Value" ""
			(at 0 0 90)
			(layer "B.Fab")
			(effects
				(font
					(size 1.27 1.27)
				)
				(justify mirror)
			)
		)
		(duplicate_pad_numbers_are_jumpers no)
		(fp_line
			(start -0.299974 0.150114)
			(end 0.299974 0.150114)
			(stroke
				(width 0.1)
				(type default)
			)
			(layer "B.Fab")
		)
		(fp_line
			(start 0.299974 0.150114)
			(end 0.299974 -0.150114)
			(stroke
				(width 0.1)
				(type default)
			)
			(layer "B.Fab")
		)
		(fp_line
			(start -0.299974 -0.150114)
			(end -0.299974 0.150114)
			(stroke
				(width 0.1)
				(type default)
			)
			(layer "B.Fab")
		)
		(fp_line
			(start 0.299974 -0.150114)
			(end -0.299974 -0.150114)
			(stroke
				(width 0.1)
				(type default)
			)
			(layer "B.Fab")
		)
		(pad "1" smd rect
			(at 0.2667 0 90)
			(size 0.3048 0.381)
			(layers "B.Cu" "B.Mask" "B.Paste")
			(net "P0V9_CPU0_RT_2D")
		)
		(pad "2" smd rect
			(at -0.2667 0 90)
			(size 0.3048 0.381)
			(layers "B.Cu" "B.Mask" "B.Paste")
			(net "GND")
		)
	)
)
